#ISCELL
  pure_quanta quanta_title_block_c *
  *
#CELL
  pure_quanta pt5161lrs *
  page438_i1
#ISCELL
  standard tap *
  page438_i10
#ISCELL
  standard tap *
  page438_i11
#ISCELL
  standard tap *
  page438_i12
#ISCELL
  standard tap *
  page438_i13
#ISCELL
  standard tap *
  page438_i14
#ISCELL
  standard tap *
  page438_i15
#ISCELL
  standard tap *
  page438_i16
#ISCELL
  standard tap *
  page438_i17
#ISCELL
  standard offpage *
  page438_i18
#ISCELL
  standard offpage *
  page438_i19
#ISCELL
  standard tap *
  page438_i2
#ISCELL
  standard tap *
  page438_i20
#ISCELL
  standard tap *
  page438_i21
#ISCELL
  standard tap *
  page438_i22
#ISCELL
  standard tap *
  page438_i23
#ISCELL
  standard tap *
  page438_i24
#ISCELL
  standard tap *
  page438_i25
#ISCELL
  standard tap *
  page438_i26
#ISCELL
  standard tap *
  page438_i27
#ISCELL
  standard tap *
  page438_i28
#ISCELL
  standard tap *
  page438_i29
#ISCELL
  standard tap *
  page438_i3
#ISCELL
  standard tap *
  page438_i30
#ISCELL
  standard tap *
  page438_i31
#ISCELL
  standard tap *
  page438_i32
#ISCELL
  standard tap *
  page438_i33
#ISCELL
  standard tap *
  page438_i34
#ISCELL
  standard tap *
  page438_i35
#ISCELL
  standard offpage *
  page438_i36
#ISCELL
  standard offpage *
  page438_i37
#CELL
  pure_quanta pt5161lrs *
  page438_i38
#ISCELL
  standard tap *
  page438_i4
#ISCELL
  standard tap *
  page438_i5
#ISCELL
  standard tap *
  page438_i6
#ISCELL
  standard tap *
  page438_i7
#ISCELL
  standard tap *
  page438_i8
#ISCELL
  standard tap *
  page438_i9
